# ZAIUS-MB-PVT-X04-BOM_X31_20180131_Final.xls.xlsx — POP_GA (bom)
| FOXCONN TECHNOLOGY GROUP |  |  |  |  |  |  |  |  |  |  |  |  |
| BILL OF MATERIAL |  |  |  |  |  |  |  |  |  |  |  |  |
| REV OF  BOM |  | CUSTOMER | <name> |  | CUSTOMER P/N |  | PRODUCT CODE |  | PWA  REV |  | DATE |  |
| Sourcing (Single/Sole/Multi) | Critical Commodity (Y or N) | Component Class (1, 2, other) | Customer PSL (Y or N) | Item Number | Foxconn P/N | Customer P/N | Part Description | Manufacturer  Full Name | Manufacturer  Part Number | Qty | RoHS Status | Location |
